# T6G (Grand Teton) — schematic netlist excerpt (pin names and nets, part order shuffled) for the footprints in the layout excerpt that follows; sources: Cadence DE-HDL packaged netlist, KiCad conversion of 04192023_DAF0TMB3IC0_F0TG_MB_C_brd_V02_OCP.brd

C1884  Q_CAP  1UF 25V 10% X6S  pkg C0402  page 233 : A = VFG_3P3A_CLK_GEN ; B = GND
R144  Q_RES  0 5% EMPTY  pkg 0402LF  page 161 : A = SMB_CPU0_CPU1_SEC_SDA_R2 ; B = SMB_CPU0_SEC_R_SDA

(kicad_pcb
	(version 20260206)
	(generator "pcbnew")
	(generator_version "10.0")
	(general
		(thickness 1.6)
		(legacy_teardrops no)
	)
	(paper "A4")
	(title_block
		(title "04192023_DAF0TMB3IC0_F0TG_MB_C_brd_V02_OCP.brd")
		(comment 1 "Grand Teton / footprints 6586-6587 of 8354")
	)
	(layers
		(0 "F.Cu" signal "TOP")
		(4 "In1.Cu" signal "GND")
		(6 "In2.Cu" signal "IN1")
		(8 "In3.Cu" signal "GND1")
		(10 "In4.Cu" signal "IN2")
		(12 "In5.Cu" signal "GND2")
		(14 "In6.Cu" signal "IN3")
		(16 "In7.Cu" signal "GND3")
		(18 "In8.Cu" signal "VCC")
		(20 "In9.Cu" signal "VCC1")
		(22 "In10.Cu" signal "GND4")
		(24 "In11.Cu" signal "IN4")
		(26 "In12.Cu" signal "GND5")
		(28 "In13.Cu" signal "IN5")
		(30 "In14.Cu" signal "GND6")
		(32 "In15.Cu" signal "IN6")
		(34 "In16.Cu" signal "GND7")
		(2 "B.Cu" signal "BOTTOM")
		(9 "F.Adhes" user "F.Adhesive")
		(11 "B.Adhes" user "B.Adhesive")
		(13 "F.Paste" user "Package Geometry/Pastemask Top")
		(15 "B.Paste" user "Package Geometry/Pastemask Bottom")
		(5 "F.SilkS" user "Ref Des/Silkscreen Top")
		(7 "B.SilkS" user "Ref Des/Silkscreen Bottom")
		(1 "F.Mask" user "Board Geometry/Soldermask Top")
		(3 "B.Mask" user "Board Geometry/Soldermask Bottom")
		(17 "Dwgs.User" user "User.Drawings")
		(19 "Cmts.User" user "User.Comments")
		(21 "Eco1.User" user "User.Eco1")
		(23 "Eco2.User" user "User.Eco2")
		(25 "Edge.Cuts" user "Board Geometry/Outline")
		(27 "Margin" user)
		(31 "F.CrtYd" user "Package Geometry/Place Bound Top")
		(29 "B.CrtYd" user "Package Geometry/Place Bound Bottom")
		(35 "F.Fab" user "Ref Des/Assembly Top")
		(33 "B.Fab" user "Ref Des/Assembly Bottom")
	)
	(footprint ""
		(layer "B.Cu")
		(at 239.395 -234.061 -90)
		(property "Reference" "R144"
			(at 0 0 90)
			(layer "B.SilkS")
			(hide yes)
			(effects
				(font
					(size 1.27 1.27)
				)
				(justify mirror)
			)
		)
		(property "Value" ""
			(at 0 0 90)
			(layer "B.Fab")
			(effects
				(font
					(size 1.27 1.27)
				)
				(justify mirror)
			)
		)
		(duplicate_pad_numbers_are_jumpers no)
		(fp_line
			(start -0.7874 0.4064)
			(end 0.7874 0.4064)
			(stroke
				(width 0.1524)
				(type default)
			)
			(layer "B.SilkS")
		)
		(fp_line
			(start 0.7874 0.4064)
			(end 0.7874 -0.4064)
			(stroke
				(width 0.1524)
				(type default)
			)
			(layer "B.SilkS")
		)
		(fp_line
			(start -0.7874 -0.4064)
			(end -0.7874 0.4064)
			(stroke
				(width 0.1524)
				(type default)
			)
			(layer "B.SilkS")
		)
		(fp_line
			(start 0.7874 -0.4064)
			(end -0.7874 -0.4064)
			(stroke
				(width 0.1524)
				(type default)
			)
			(layer "B.SilkS")
		)
		(fp_line
			(start -0.67945 0.3048)
			(end -0.120396 0.3048)
			(stroke
				(width 0.1)
				(type default)
			)
			(layer "B.Fab")
		)
		(fp_line
			(start -0.120396 0.3048)
			(end -0.120396 0.2794)
			(stroke
				(width 0.1)
				(type default)
			)
			(layer "B.Fab")
		)
		(fp_line
			(start 0.12065 0.3048)
			(end 0.67945 0.3048)
			(stroke
				(width 0.1)
				(type default)
			)
			(layer "B.Fab")
		)
		(fp_line
			(start 0.67945 0.3048)
			(end 0.67945 -0.305054)
			(stroke
				(width 0.1)
				(type default)
			)
			(layer "B.Fab")
		)
		(fp_line
			(start -0.120396 0.2794)
			(end 0.12065 0.2794)
			(stroke
				(width 0.1)
				(type default)
			)
			(layer "B.Fab")
		)
		(fp_line
			(start 0.12065 0.2794)
			(end 0.12065 0.3048)
			(stroke
				(width 0.1)
				(type default)
			)
			(layer "B.Fab")
		)
		(fp_line
			(start -0.12065 -0.2794)
			(end -0.12065 -0.3048)
			(stroke
				(width 0.1)
				(type default)
			)
			(layer "B.Fab")
		)
		(fp_line
			(start 0.12065 -0.2794)
			(end -0.12065 -0.2794)
			(stroke
				(width 0.1)
				(type default)
			)
			(layer "B.Fab")
		)
		(fp_line
			(start -0.67945 -0.3048)
			(end -0.67945 0.3048)
			(stroke
				(width 0.1)
				(type default)
			)
			(layer "B.Fab")
		)
		(fp_line
			(start -0.12065 -0.3048)
			(end -0.67945 -0.3048)
			(stroke
				(width 0.1)
				(type default)
			)
			(layer "B.Fab")
		)
		(fp_line
			(start 0.12065 -0.305054)
			(end 0.12065 -0.2794)
			(stroke
				(width 0.1)
				(type default)
			)
			(layer "B.Fab")
		)
		(fp_line
			(start 0.67945 -0.305054)
			(end 0.12065 -0.305054)
			(stroke
				(width 0.1)
				(type default)
			)
			(layer "B.Fab")
		)
		(pad "1" smd circle
			(at 0.40005 0 90)
			(size 0 0)
			(layers "B.Cu" "B.Mask" "B.Paste")
			(net "SMB_CPU0_CPU1_SEC_SDA_R2")
		)
		(pad "2" smd circle
			(at -0.40005 0 90)
			(size 0 0)
			(layers "B.Cu" "B.Mask" "B.Paste")
			(net "SMB_CPU0_SEC_R_SDA")
		)
	)
	(footprint ""
		(layer "B.Cu")
		(at 15.448788 -132.78993 90)
		(property "Reference" "C1884"
			(at 0 0 90)
			(layer "B.SilkS")
			(hide yes)
			(effects
				(font
					(size 1.27 1.27)
				)
				(justify mirror)
			)
		)
		(property "Value" ""
			(at 0 0 90)
			(layer "B.Fab")
			(effects
				(font
					(size 1.27 1.27)
				)
				(justify mirror)
			)
		)
		(duplicate_pad_numbers_are_jumpers no)
		(fp_line
			(start 0.7874 -0.4064)
			(end -0.7874 -0.4064)
			(stroke
				(width 0.1524)
				(type default)
			)
			(layer "B.SilkS")
		)
		(fp_line
			(start -0.7874 -0.4064)
			(end -0.7874 0.4064)
			(stroke
				(width 0.1524)
				(type default)
			)
			(layer "B.SilkS")
		)
		(fp_line
			(start 0.7874 0.4064)
			(end 0.7874 -0.4064)
			(stroke
				(width 0.1524)
				(type default)
			)
			(layer "B.SilkS")
		)
		(fp_line
			(start -0.7874 0.4064)
			(end 0.7874 0.4064)
			(stroke
				(width 0.1524)
				(type default)
			)
			(layer "B.SilkS")
		)
		(fp_line
			(start 0.67945 -0.305054)
			(end 0.12065 -0.305054)
			(stroke
				(width 0.1)
				(type default)
			)
			(layer "B.Fab")
		)
		(fp_line
			(start 0.12065 -0.305054)
			(end 0.12065 -0.2794)
			(stroke
				(width 0.1)
				(type default)
			)
			(layer "B.Fab")
		)
		(fp_line
			(start -0.12065 -0.3048)
			(end -0.67945 -0.3048)
			(stroke
				(width 0.1)
				(type default)
			)
			(layer "B.Fab")
		)
		(fp_line
			(start -0.67945 -0.3048)
			(end -0.67945 0.3048)
			(stroke
				(width 0.1)
				(type default)
			)
			(layer "B.Fab")
		)
		(fp_line
			(start 0.12065 -0.2794)
			(end -0.12065 -0.2794)
			(stroke
				(width 0.1)
				(type default)
			)
			(layer "B.Fab")
		)
		(fp_line
			(start -0.12065 -0.2794)
			(end -0.12065 -0.3048)
			(stroke
				(width 0.1)
				(type default)
			)
			(layer "B.Fab")
		)
		(fp_line
			(start 0.12065 0.2794)
			(end 0.12065 0.3048)
			(stroke
				(width 0.1)
				(type default)
			)
			(layer "B.Fab")
		)
		(fp_line
			(start -0.120396 0.2794)
			(end 0.12065 0.2794)
			(stroke
				(width 0.1)
				(type default)
			)
			(layer "B.Fab")
		)
		(fp_line
			(start 0.67945 0.3048)
			(end 0.67945 -0.305054)
			(stroke
				(width 0.1)
				(type default)
			)
			(layer "B.Fab")
		)
		(fp_line
			(start 0.12065 0.3048)
			(end 0.67945 0.3048)
			(stroke
				(width 0.1)
				(type default)
			)
			(layer "B.Fab")
		)
		(fp_line
			(start -0.120396 0.3048)
			(end -0.120396 0.2794)
			(stroke
				(width 0.1)
				(type default)
			)
			(layer "B.Fab")
		)
		(fp_line
			(start -0.67945 0.3048)
			(end -0.120396 0.3048)
			(stroke
				(width 0.1)
				(type default)
			)
			(layer "B.Fab")
		)
		(pad "1" smd circle
			(at 0.40005 0 270)
			(size 0 0)
			(layers "B.Cu" "B.Mask" "B.Paste")
			(net "VFG_3P3A_CLK_GEN")
		)
		(pad "2" smd circle
			(at -0.40005 0 270)
			(size 0 0)
			(layers "B.Cu" "B.Mask" "B.Paste")
			(net "GND")
		)
	)
)
